FILE_TYPE = MACRO_DRAWING;
SET COLOR_WIRE YELLOW;
SET COLOR_PROP ORANGE;
SET COLOR_DOT WHITE;
SET COLOR_ARC YELLOW;
SET COLOR_BODY GREEN;
SET COLOR_NOTE PURPLE;
SET PROP_DISPLAY VALUE;
SET PAGE_NUMBER P436;
FORCEADD QUANTA_TITLE_BLOCK_C..1
(0 0);
FORCEPROP 1 LAST CUSTOM_TXT_CDS <NAME_2>
J 0
(-3175 50);
FORCEPROP 1 LAST CUSTOM_TXT_CDS <NAME_1>
J 0
(-3175 175);
FORCEPROP 1 LAST CUSTOM_TXT_CDS <Q_NUMBER>
J 0
(-1403 103);
DISPLAY 1.212766 (-1403 103);
FORCEPROP 1 LAST CUSTOM_TXT_CDS <Q_PROJ>
J 0
(-2382 102);
DISPLAY 1.212766 (-2382 102);
FORCEPROP 1 LAST CUSTOM_TXT_CDS <Q_REV>
J 0
(-184 103);
DISPLAY 1.212766 (-184 103);
FORCEPROP 1 LAST CUSTOM_TXT_CDS <CON_LAST_MODIFIED>
J 0
(-1885 15);
DISPLAY 0.978723 (-1885 15);
FORCEPROP 1 LAST CUSTOM_TXT_CDS <CON_PAGE_NUM> OF <CON_TOTAL_PAGES>
J 0
(-446 18);
DISPLAY 0.978723 (-446 18);
FORCEPROP 1 LAST Q_TITLE BLANK
J 0
(-9366 26);
DISPLAY 2.446809 (-9366 26);
PAINT GREEN (-9366 26);
FORCEPROP 2 LAST CDS_LIB pure_quanta
J 0
(0 0);
DISPLAY INVISIBLE (0 0);
FORCEPROP 1 LAST CDS_LMAN_SYM_OUTLINE -9475,6775,100,-125
J 0
(0 0);
DISPLAY 0.468085 (0 0);
PAINT GREEN (0 0);
DISPLAY INVISIBLE (0 0);
FORCEPROP 2 LAST PAGE_BORDER TRUE
J 0
(-7890 5250);
DISPLAY 0.638298 (-7890 5250);
PAINT PINK (-7890 5250);
DISPLAY INVISIBLE (-7890 5250);
FORCEPROP 2 LAST CDS_XR_PAGE_TITLE CR-316 : @T6G_MB_LIB.T6G(SCH_1):PAGE316
J 0
(-7890 5250);
DISPLAY 0.638298 (-7890 5250);
PAINT PINK (-7890 5250);
DISPLAY INVISIBLE (-7890 5250);
FORCEPROP 2 LAST CUSTOM_TXT_CDS <XR_PAGE_TITLE>
J 0
(-7890 5250);
DISPLAY 0.638298 (-7890 5250);
PAINT PINK (-7890 5250);
DISPLAY INVISIBLE (-7890 5250);
FORCEPROP 1 LAST COMMENT_BODY TRUE
J 0
(12 -13);
DISPLAY 0.978723 (12 -13);
PAINT GREEN (12 -13);
DISPLAY INVISIBLE (12 -13);
FORCEPROP 1 LAST Q_DEPT BU9
J 1
(-3763 49);
DISPLAY 1.957447 (-3763 49);
PAINT GREEN (-3763 49);
DISPLAY INVISIBLE (-3763 49);
FORCEPROP 0 LAST CDS_CON_LAST_MODIFIED Thu Aug 24 10:16:37 2023
J 0
(-1885 15);
DISPLAY INVISIBLE (-1885 15);
QUIT
